(kicad_pcb
	(version 20241229)
	(generator "pcbnew")
	(generator_version "9.0")
	(general
		(thickness 1.711)
		(legacy_teardrops no)
	)
	(paper "A4")
	(title_block
		(title "Antmicro Baseboard for Jetson AGX Thor")
		(date "2026-02-18")
		(rev "1.1.0")
		(company "Antmicro Ltd")
		(comment 1 "www.antmicro.com")
		(comment 9 "footprints 1055-1060 of 1170")
	)
	(layers
		(0 "F.Cu" signal)
		(4 "In1.Cu" signal)
		(6 "In2.Cu" signal)
		(8 "In3.Cu" signal)
		(10 "In4.Cu" jumper)
		(12 "In5.Cu" signal)
		(14 "In6.Cu" signal)
		(16 "In7.Cu" signal)
		(18 "In8.Cu" signal)
		(2 "B.Cu" signal)
		(9 "F.Adhes" user "F.Adhesive")
		(11 "B.Adhes" user "B.Adhesive")
		(13 "F.Paste" user)
		(15 "B.Paste" user)
		(5 "F.SilkS" user "F.Silkscreen")
		(7 "B.SilkS" user "B.Silkscreen")
		(1 "F.Mask" user)
		(3 "B.Mask" user)
		(17 "Dwgs.User" user "User.Drawings")
		(19 "Cmts.User" user "User.Comments")
		(21 "Eco1.User" user "User.Eco1")
		(23 "Eco2.User" user "User.Eco2")
		(25 "Edge.Cuts" user)
		(27 "Margin" user)
		(31 "F.CrtYd" user "F.Courtyard")
		(29 "B.CrtYd" user "B.Courtyard")
		(35 "F.Fab" user)
		(33 "B.Fab" user)
	)
	(footprint "antmicro-footprints:R_0402_1005Metric"
		(layer "B.Cu")
		(at 195.9 87.8 90)
		(descr "Resistor SMD 0402")
		(tags "resistor SMD 0402")
		(property "Reference" "R382"
			(at -3.7 -0.4 90)
			(layer "B.SilkS")
			(effects
				(font
					(size 0.7 0.7)
					(thickness 0.15)
				)
				(justify right top mirror)
			)
		)
		(property "Value" "R_0R_0402"
			(at -1.011843 -1.772047 90)
			(layer "B.Fab")
			(effects
				(font
					(size 0.7 0.7)
					(thickness 0.15)
				)
				(justify right top mirror)
			)
		)
		(property "Datasheet" "https://industrial.panasonic.com/cdbs/www-data/pdf/RDA0000/AOA0000C301.pdf"
			(at 0 0 90)
			(layer "B.Fab")
			(hide yes)
			(effects
				(font
					(size 1.27 1.27)
					(thickness 0.15)
				)
				(justify mirror)
			)
		)
		(property "Description" "SMD Chip Resistor, Jumper, 0 ohm, 100 mW, 0402 [1005 Metric], Thick Film, General Purpose"
			(at 0 0 90)
			(layer "B.Fab")
			(hide yes)
			(effects
				(font
					(size 1.27 1.27)
					(thickness 0.15)
				)
				(justify mirror)
			)
		)
		(property "MPN" "ERJ2GE0R00X"
			(at 0 0 270)
			(unlocked yes)
			(layer "B.Fab")
			(hide yes)
			(effects
				(font
					(size 1 1)
					(thickness 0.15)
				)
				(justify mirror)
			)
		)
		(property "Manufacturer" "Panasonic"
			(at 0 0 270)
			(unlocked yes)
			(layer "B.Fab")
			(hide yes)
			(effects
				(font
					(size 1 1)
					(thickness 0.15)
				)
				(justify mirror)
			)
		)
		(property "License" "Apache-2.0"
			(at 0 0 270)
			(unlocked yes)
			(layer "B.Fab")
			(hide yes)
			(effects
				(font
					(size 1 1)
					(thickness 0.15)
				)
				(justify mirror)
			)
		)
		(property "Author" "Antmicro"
			(at 0 0 270)
			(unlocked yes)
			(layer "B.Fab")
			(hide yes)
			(effects
				(font
					(size 1 1)
					(thickness 0.15)
				)
				(justify mirror)
			)
		)
		(property "Val" "0R"
			(at 0 0 270)
			(unlocked yes)
			(layer "B.Fab")
			(hide yes)
			(effects
				(font
					(size 1 1)
					(thickness 0.15)
				)
				(justify mirror)
			)
		)
		(property "Tolerance" "~"
			(at 0 0 270)
			(unlocked yes)
			(layer "B.Fab")
			(hide yes)
			(effects
				(font
					(size 1 1)
					(thickness 0.15)
				)
				(justify mirror)
			)
		)
		(property "Current" "1A"
			(at 0 0 270)
			(unlocked yes)
			(layer "B.Fab")
			(hide yes)
			(effects
				(font
					(size 1 1)
					(thickness 0.15)
				)
				(justify mirror)
			)
		)
		(sheetname "/USB Debug, PD/")
		(sheetfile "usb_debug_pd.kicad_sch")
		(attr smd)
		(fp_rect
			(start -0.925 0.47)
			(end 0.925 -0.47)
			(stroke
				(width 0.05)
				(type default)
			)
			(fill no)
			(layer "B.CrtYd")
		)
		(fp_rect
			(start -0.5 0.25)
			(end 0.5 -0.25)
			(stroke
				(width 0.15)
				(type solid)
			)
			(fill no)
			(layer "B.Fab")
		)
		(fp_text user "Author: Antmicro"
			(at -0.95 -4.169 90)
			(layer "B.Fab")
			(effects
				(font
					(size 0.7 0.7)
					(thickness 0.15)
				)
				(justify right top mirror)
			)
		)
		(fp_text user "License: Apache-2.0"
			(at -0.95 -5.169 90)
			(layer "B.Fab")
			(effects
				(font
					(size 0.7 0.7)
					(thickness 0.15)
				)
				(justify right top mirror)
			)
		)
		(fp_text user "${REFERENCE}"
			(at -0.95 -3.168 90)
			(layer "B.Fab")
			(effects
				(font
					(size 0.7 0.7)
					(thickness 0.15)
				)
				(justify right top mirror)
			)
		)
		(pad "1" smd roundrect
			(at -0.48 0 90)
			(size 0.59 0.64)
			(layers "B.Cu" "B.Mask" "B.Paste")
			(roundrect_rratio 0.25)
			(net 811 "/USB Debug, PD/MOSI")
			(pintype "passive")
		)
		(pad "2" smd roundrect
			(at 0.48 0 90)
			(size 0.59 0.64)
			(layers "B.Cu" "B.Mask" "B.Paste")
			(roundrect_rratio 0.25)
			(net 940 "/USB Debug, PD/PDC_MOSI")
			(pintype "passive")
		)
	)
	(footprint "antmicro-footprints:TP_SMD_0.75mm"
		(layer "B.Cu")
		(at 199 73.6 180)
		(property "Reference" "TP92"
			(at -1.3 0.6 0)
			(layer "B.SilkS")
			(effects
				(font
					(size 0.7 0.7)
					(thickness 0.15)
				)
				(justify left bottom mirror)
			)
		)
		(property "Value" "TP_0.75mm_SMD"
			(at 0 -1.2 0)
			(layer "B.Fab")
			(effects
				(font
					(size 0.7 0.7)
					(thickness 0.15)
				)
				(justify left bottom mirror)
			)
		)
		(property "Description" "SMT test point"
			(at 0 0 0)
			(layer "B.Fab")
			(hide yes)
			(effects
				(font
					(size 1.27 1.27)
					(thickness 0.15)
				)
				(justify mirror)
			)
		)
		(property "MPN" ""
			(at 0 0 0)
			(unlocked yes)
			(layer "B.Fab")
			(hide yes)
			(effects
				(font
					(size 1 1)
					(thickness 0.15)
				)
				(justify mirror)
			)
		)
		(property "Manufacturer" ""
			(at 0 0 0)
			(unlocked yes)
			(layer "B.Fab")
			(hide yes)
			(effects
				(font
					(size 1 1)
					(thickness 0.15)
				)
				(justify mirror)
			)
		)
		(property "Author" "Antmicro"
			(at 0 0 0)
			(unlocked yes)
			(layer "B.Fab")
			(hide yes)
			(effects
				(font
					(size 1 1)
					(thickness 0.15)
				)
				(justify mirror)
			)
		)
		(property "License" "Apache-2.0"
			(at 0 0 0)
			(unlocked yes)
			(layer "B.Fab")
			(hide yes)
			(effects
				(font
					(size 1 1)
					(thickness 0.15)
				)
				(justify mirror)
			)
		)
		(sheetname "/USB Debug, PD/")
		(sheetfile "usb_debug_pd.kicad_sch")
		(attr exclude_from_pos_files exclude_from_bom)
		(fp_circle
			(center 0 0)
			(end 0.475 0)
			(stroke
				(width 0.05)
				(type default)
			)
			(fill no)
			(layer "B.CrtYd")
		)
		(fp_text user "Author: Antmicro"
			(at -0.4 -3.901 0)
			(layer "B.Fab")
			(effects
				(font
					(size 0.7 0.7)
					(thickness 0.15)
				)
				(justify left bottom mirror)
			)
		)
		(fp_text user "License: Apache-2.0"
			(at -0.4 -5.101 0)
			(layer "B.Fab")
			(effects
				(font
					(size 0.7 0.7)
					(thickness 0.15)
				)
				(justify left bottom mirror)
			)
		)
		(fp_text user "${REFERENCE}"
			(at -0.4 -2.7 0)
			(layer "B.Fab")
			(effects
				(font
					(size 0.7 0.7)
					(thickness 0.15)
				)
				(justify left bottom mirror)
			)
		)
		(pad "1" smd circle
			(at 0 0 180)
			(size 0.75 0.75)
			(layers "B.Cu" "B.Mask")
			(net 945 "/USB Debug, PD/DEBUG_SCL")
			(pinfunction "1")
			(pintype "passive")
		)
	)
	(footprint "antmicro-footprints:TP_SMD_0.75mm"
		(layer "B.Cu")
		(at 141.3 76.65 90)
		(property "Reference" "TP8"
			(at -0.98 -1.42 90)
			(layer "B.SilkS")
			(effects
				(font
					(size 0.7 0.7)
					(thickness 0.15)
				)
				(justify right top mirror)
			)
		)
		(property "Value" "TP_0.75mm_SMD"
			(at 0 -1.2 90)
			(layer "B.Fab")
			(effects
				(font
					(size 0.7 0.7)
					(thickness 0.15)
				)
				(justify right top mirror)
			)
		)
		(property "Description" "SMT test point"
			(at 0 0 90)
			(layer "B.Fab")
			(hide yes)
			(effects
				(font
					(size 1.27 1.27)
					(thickness 0.15)
				)
				(justify mirror)
			)
		)
		(property "MPN" ""
			(at 0 0 270)
			(unlocked yes)
			(layer "B.Fab")
			(hide yes)
			(effects
				(font
					(size 1 1)
					(thickness 0.15)
				)
				(justify mirror)
			)
		)
		(property "Manufacturer" ""
			(at 0 0 270)
			(unlocked yes)
			(layer "B.Fab")
			(hide yes)
			(effects
				(font
					(size 1 1)
					(thickness 0.15)
				)
				(justify mirror)
			)
		)
		(property "Author" "Antmicro"
			(at 0 0 270)
			(unlocked yes)
			(layer "B.Fab")
			(hide yes)
			(effects
				(font
					(size 1 1)
					(thickness 0.15)
				)
				(justify mirror)
			)
		)
		(property "License" "Apache-2.0"
			(at 0 0 270)
			(unlocked yes)
			(layer "B.Fab")
			(hide yes)
			(effects
				(font
					(size 1 1)
					(thickness 0.15)
				)
				(justify mirror)
			)
		)
		(sheetname "/SoM_Power/")
		(sheetfile "som_power.kicad_sch")
		(attr exclude_from_pos_files exclude_from_bom)
		(fp_circle
			(center 0 0)
			(end 0.475 0)
			(stroke
				(width 0.05)
				(type default)
			)
			(fill no)
			(layer "B.CrtYd")
		)
		(fp_text user "${REFERENCE}"
			(at -0.4 -2.7 90)
			(layer "B.Fab")
			(effects
				(font
					(size 0.7 0.7)
					(thickness 0.15)
				)
				(justify right top mirror)
			)
		)
		(fp_text user "Author: Antmicro"
			(at -0.4 -3.901 90)
			(layer "B.Fab")
			(effects
				(font
					(size 0.7 0.7)
					(thickness 0.15)
				)
				(justify right top mirror)
			)
		)
		(fp_text user "License: Apache-2.0"
			(at -0.4 -5.101 90)
			(layer "B.Fab")
			(effects
				(font
					(size 0.7 0.7)
					(thickness 0.15)
				)
				(justify right top mirror)
			)
		)
		(pad "1" smd circle
			(at 0 0 90)
			(size 0.75 0.75)
			(layers "B.Cu" "B.Mask")
			(net 673 "Net-(J1A-THERM_SHDN_REQ_N)")
			(pinfunction "1")
			(pintype "passive")
		)
	)
	(footprint "antmicro-footprints:Mech_M2_2280_H2.5mm"
		(layer "B.Cu")
		(at 197.665 104.6405 90)
		(property "Reference" "A1"
			(at 0 -8.89 90)
			(layer "B.SilkS")
			(hide yes)
			(effects
				(font
					(size 0.7 0.7)
					(thickness 0.15)
				)
				(justify left bottom mirror)
			)
		)
		(property "Value" "Mech_M2_2280_H2.5mm"
			(at 0 -6.857 90)
			(layer "B.Fab")
			(effects
				(font
					(size 0.7 0.7)
					(thickness 0.15)
				)
				(justify left bottom mirror)
			)
		)
		(property "Description" "Mechanical model for M2 2280 2.5mm module"
			(at 0 0 90)
			(layer "B.Fab")
			(hide yes)
			(effects
				(font
					(size 1.27 1.27)
					(thickness 0.15)
				)
				(justify mirror)
			)
		)
		(property "Manufacturer" ""
			(at 0 0 270)
			(unlocked yes)
			(layer "B.Fab")
			(hide yes)
			(effects
				(font
					(size 1 1)
					(thickness 0.15)
				)
				(justify mirror)
			)
		)
		(property "MPN" ""
			(at 0 0 270)
			(unlocked yes)
			(layer "B.Fab")
			(hide yes)
			(effects
				(font
					(size 1 1)
					(thickness 0.15)
				)
				(justify mirror)
			)
		)
		(property "Author" "Antmicro"
			(at 0 0 270)
			(unlocked yes)
			(layer "B.Fab")
			(hide yes)
			(effects
				(font
					(size 1 1)
					(thickness 0.15)
				)
				(justify mirror)
			)
		)
		(property "License" "Apache-2.0"
			(at 0 0 270)
			(unlocked yes)
			(layer "B.Fab")
			(hide yes)
			(effects
				(font
					(size 1 1)
					(thickness 0.15)
				)
				(justify mirror)
			)
		)
		(sheetname "/M.2/")
		(sheetfile "m2.kicad_sch")
		(attr exclude_from_pos_files exclude_from_bom allow_missing_courtyard dnp)
		(fp_rect
			(start -10.922 -0.0508)
			(end 11.0236 -80.0608)
			(stroke
				(width 0.15)
				(type solid)
			)
			(fill no)
			(layer "B.Fab")
		)
		(fp_text user "Author: Antmicro"
			(at -12.2428 -83.1912 90)
			(layer "B.Fab")
			(effects
				(font
					(size 0.7 0.7)
					(thickness 0.15)
				)
				(justify right top mirror)
			)
		)
		(fp_text user "License: Apache-2.0"
			(at -12.2428 -84.3922 90)
			(layer "B.Fab")
			(effects
				(font
					(size 0.7 0.7)
					(thickness 0.15)
				)
				(justify right top mirror)
			)
		)
		(fp_text user "${REFERENCE}"
			(at -12.2428 -81.9912 90)
			(layer "B.Fab")
			(effects
				(font
					(size 0.7 0.7)
					(thickness 0.15)
				)
				(justify right top mirror)
			)
		)
	)
	(footprint "antmicro-footprints:R_0402_1005Metric"
		(layer "B.Cu")
		(at 124.6 133.925)
		(descr "Resistor SMD 0402")
		(tags "resistor SMD 0402")
		(property "Reference" "R226"
			(at -1.2 -5.55 0)
			(layer "B.SilkS")
			(effects
				(font
					(size 0.7 0.7)
					(thickness 0.15)
				)
				(justify right top mirror)
			)
		)
		(property "Value" "R_0R_0402"
			(at -1.011843 -1.772046 0)
			(layer "B.Fab")
			(effects
				(font
					(size 0.7 0.7)
					(thickness 0.15)
				)
				(justify right top mirror)
			)
		)
		(property "Datasheet" "https://industrial.panasonic.com/cdbs/www-data/pdf/RDA0000/AOA0000C301.pdf"
			(at 0 0 0)
			(layer "B.Fab")
			(hide yes)
			(effects
				(font
					(size 1.27 1.27)
					(thickness 0.15)
				)
				(justify mirror)
			)
		)
		(property "Description" "SMD Chip Resistor, Jumper, 0 ohm, 100 mW, 0402 [1005 Metric], Thick Film, General Purpose"
			(at 0 0 0)
			(layer "B.Fab")
			(hide yes)
			(effects
				(font
					(size 1.27 1.27)
					(thickness 0.15)
				)
				(justify mirror)
			)
		)
		(property "Manufacturer" "Panasonic"
			(at 0 0 180)
			(unlocked yes)
			(layer "B.Fab")
			(hide yes)
			(effects
				(font
					(size 1 1)
					(thickness 0.15)
				)
				(justify mirror)
			)
		)
		(property "MPN" "ERJ2GE0R00X"
			(at 0 0 180)
			(unlocked yes)
			(layer "B.Fab")
			(hide yes)
			(effects
				(font
					(size 1 1)
					(thickness 0.15)
				)
				(justify mirror)
			)
		)
		(property "Val" "0R"
			(at 0 0 180)
			(unlocked yes)
			(layer "B.Fab")
			(hide yes)
			(effects
				(font
					(size 1 1)
					(thickness 0.15)
				)
				(justify mirror)
			)
		)
		(property "License" "Apache-2.0"
			(at 0 0 180)
			(unlocked yes)
			(layer "B.Fab")
			(hide yes)
			(effects
				(font
					(size 1 1)
					(thickness 0.15)
				)
				(justify mirror)
			)
		)
		(property "Author" "Antmicro"
			(at 0 0 180)
			(unlocked yes)
			(layer "B.Fab")
			(hide yes)
			(effects
				(font
					(size 1 1)
					(thickness 0.15)
				)
				(justify mirror)
			)
		)
		(property "Tolerance" "~"
			(at 0 0 180)
			(unlocked yes)
			(layer "B.Fab")
			(hide yes)
			(effects
				(font
					(size 1 1)
					(thickness 0.15)
				)
				(justify mirror)
			)
		)
		(property "Current" "1A"
			(at 0 0 0)
			(unlocked yes)
			(layer "B.Fab")
			(hide yes)
			(effects
				(font
					(size 1 1)
					(thickness 0.15)
				)
				(justify mirror)
			)
		)
		(property "Public" "False"
			(at 0 0 0)
			(unlocked yes)
			(layer "B.Fab")
			(hide yes)
			(effects
				(font
					(size 1 1)
					(thickness 0.15)
				)
				(justify mirror)
			)
		)
		(sheetname "/M.2/")
		(sheetfile "m2.kicad_sch")
		(attr smd)
		(fp_poly
			(pts
				(xy -0.925 0.47) (xy 0.925 0.47) (xy 0.925 -0.47) (xy -0.925 -0.47)
			)
			(stroke
				(width 0.05)
				(type default)
			)
			(fill no)
			(layer "B.CrtYd")
		)
		(fp_poly
			(pts
				(xy -0.5 0.25) (xy 0.5 0.25) (xy 0.5 -0.25) (xy -0.5 -0.25)
			)
			(stroke
				(width 0.15)
				(type solid)
			)
			(fill no)
			(layer "B.Fab")
		)
		(fp_text user "Author: Antmicro"
			(at -0.95 -4.169 0)
			(layer "B.Fab")
			(effects
				(font
					(size 0.7 0.7)
					(thickness 0.15)
				)
				(justify right top mirror)
			)
		)
		(fp_text user "${REFERENCE}"
			(at -0.95 -3.168 0)
			(layer "B.Fab")
			(effects
				(font
					(size 0.7 0.7)
					(thickness 0.15)
				)
				(justify right top mirror)
			)
		)
		(fp_text user "License: Apache-2.0"
			(at -0.949999 -5.169 0)
			(layer "B.Fab")
			(effects
				(font
					(size 0.7 0.7)
					(thickness 0.15)
				)
				(justify right top mirror)
			)
		)
		(pad "1" smd roundrect
			(at -0.48 0)
			(size 0.59 0.64)
			(layers "B.Cu" "B.Mask" "B.Paste")
			(roundrect_rratio 0.25)
			(net 247 "/M.2/M2_E_W_DIS_2")
			(pintype "passive")
		)
		(pad "2" smd roundrect
			(at 0.48 0)
			(size 0.59 0.64)
			(layers "B.Cu" "B.Mask" "B.Paste")
			(roundrect_rratio 0.25)
			(net 1167 "/M.2/M2_E.W_DIS_2")
			(pintype "passive")
		)
	)
	(footprint "antmicro-footprints:TP_SMD_0.75mm"
		(layer "B.Cu")
		(at 140.45 128.7)
		(property "Reference" "TP86"
			(at -0.85 0.5 180)
			(layer "B.SilkS")
			(effects
				(font
					(size 0.7 0.7)
					(thickness 0.15)
				)
				(justify left bottom mirror)
			)
		)
		(property "Value" "TP_0.75mm_SMD"
			(at 0 -1.2 180)
			(layer "B.Fab")
			(effects
				(font
					(size 0.7 0.7)
					(thickness 0.15)
				)
				(justify left bottom mirror)
			)
		)
		(property "Description" "SMT test point"
			(at 0 0 180)
			(layer "B.Fab")
			(hide yes)
			(effects
				(font
					(size 1.27 1.27)
					(thickness 0.15)
				)
				(justify mirror)
			)
		)
		(property "MPN" ""
			(at 0 0 180)
			(unlocked yes)
			(layer "B.Fab")
			(hide yes)
			(effects
				(font
					(size 1 1)
					(thickness 0.15)
				)
				(justify mirror)
			)
		)
		(property "Manufacturer" ""
			(at 0 0 180)
			(unlocked yes)
			(layer "B.Fab")
			(hide yes)
			(effects
				(font
					(size 1 1)
					(thickness 0.15)
				)
				(justify mirror)
			)
		)
		(property "Author" "Antmicro"
			(at 0 0 180)
			(unlocked yes)
			(layer "B.Fab")
			(hide yes)
			(effects
				(font
					(size 1 1)
					(thickness 0.15)
				)
				(justify mirror)
			)
		)
		(property "License" "Apache-2.0"
			(at 0 0 180)
			(unlocked yes)
			(layer "B.Fab")
			(hide yes)
			(effects
				(font
					(size 1 1)
					(thickness 0.15)
				)
				(justify mirror)
			)
		)
		(sheetname "/SoM_Power/")
		(sheetfile "som_power.kicad_sch")
		(attr exclude_from_pos_files exclude_from_bom)
		(fp_circle
			(center 0 0)
			(end 0.475 0)
			(stroke
				(width 0.05)
				(type default)
			)
			(fill no)
			(layer "B.CrtYd")
		)
		(fp_text user "Author: Antmicro"
			(at -0.4 -3.901 180)
			(layer "B.Fab")
			(effects
				(font
					(size 0.7 0.7)
					(thickness 0.15)
				)
				(justify left bottom mirror)
			)
		)
		(fp_text user "License: Apache-2.0"
			(at -0.4 -5.101 180)
			(layer "B.Fab")
			(effects
				(font
					(size 0.7 0.7)
					(thickness 0.15)
				)
				(justify left bottom mirror)
			)
		)
		(fp_text user "${REFERENCE}"
			(at -0.4 -2.7 180)
			(layer "B.Fab")
			(effects
				(font
					(size 0.7 0.7)
					(thickness 0.15)
				)
				(justify left bottom mirror)
			)
		)
		(pad "1" smd circle
			(at 0 0)
			(size 0.75 0.75)
			(layers "B.Cu" "B.Mask")
			(net 1293 "/DCDC/CARRIER_PWR_ON")
			(pinfunction "1")
			(pintype "passive")
		)
	)
)
